# T6G (Grand Teton) — schematic netlist excerpt (pin names and nets, part order shuffled) for the footprints in the layout excerpt that follows; sources: Cadence DE-HDL packaged netlist, KiCad conversion of 04192023_DAF0TMB3IC0_F0TG_MB_C_brd_V02_OCP.brd

C6110  Q_CAP  0.01UF 50V 10% X7R  pkg C0402  page 179 : A = P1V2_CPU0_USB2_DVDD12 ; B = GND

(kicad_pcb
	(version 20260206)
	(generator "pcbnew")
	(generator_version "10.0")
	(general
		(thickness 1.6)
		(legacy_teardrops no)
	)
	(paper "A4")
	(title_block
		(title "04192023_DAF0TMB3IC0_F0TG_MB_C_brd_V02_OCP.brd")
		(comment 1 "Grand Teton / footprints 7490-7490 of 8354")
	)
	(layers
		(0 "F.Cu" signal "TOP")
		(4 "In1.Cu" signal "GND")
		(6 "In2.Cu" signal "IN1")
		(8 "In3.Cu" signal "GND1")
		(10 "In4.Cu" signal "IN2")
		(12 "In5.Cu" signal "GND2")
		(14 "In6.Cu" signal "IN3")
		(16 "In7.Cu" signal "GND3")
		(18 "In8.Cu" signal "VCC")
		(20 "In9.Cu" signal "VCC1")
		(22 "In10.Cu" signal "GND4")
		(24 "In11.Cu" signal "IN4")
		(26 "In12.Cu" signal "GND5")
		(28 "In13.Cu" signal "IN5")
		(30 "In14.Cu" signal "GND6")
		(32 "In15.Cu" signal "IN6")
		(34 "In16.Cu" signal "GND7")
		(2 "B.Cu" signal "BOTTOM")
		(9 "F.Adhes" user "F.Adhesive")
		(11 "B.Adhes" user "B.Adhesive")
		(13 "F.Paste" user "Package Geometry/Pastemask Top")
		(15 "B.Paste" user "Package Geometry/Pastemask Bottom")
		(5 "F.SilkS" user "Ref Des/Silkscreen Top")
		(7 "B.SilkS" user "Ref Des/Silkscreen Bottom")
		(1 "F.Mask" user "Board Geometry/Soldermask Top")
		(3 "B.Mask" user "Board Geometry/Soldermask Bottom")
		(17 "Dwgs.User" user "User.Drawings")
		(19 "Cmts.User" user "User.Comments")
		(21 "Eco1.User" user "User.Eco1")
		(23 "Eco2.User" user "User.Eco2")
		(25 "Edge.Cuts" user "Board Geometry/Outline")
		(27 "Margin" user)
		(31 "F.CrtYd" user "Package Geometry/Place Bound Top")
		(29 "B.CrtYd" user "Package Geometry/Place Bound Bottom")
		(35 "F.Fab" user "Ref Des/Assembly Top")
		(33 "B.Fab" user "Ref Des/Assembly Bottom")
	)
	(footprint ""
		(layer "B.Cu")
		(at 112.46866 -35.088068 90)
		(property "Reference" "C6110"
			(at 0 0 90)
			(layer "B.SilkS")
			(hide yes)
			(effects
				(font
					(size 1.27 1.27)
				)
				(justify mirror)
			)
		)
		(property "Value" ""
			(at 0 0 90)
			(layer "B.Fab")
			(effects
				(font
					(size 1.27 1.27)
				)
				(justify mirror)
			)
		)
		(duplicate_pad_numbers_are_jumpers no)
		(fp_line
			(start 0.7874 -0.4064)
			(end -0.7874 -0.4064)
			(stroke
				(width 0.1524)
				(type default)
			)
			(layer "B.SilkS")
		)
		(fp_line
			(start -0.7874 -0.4064)
			(end -0.7874 0.4064)
			(stroke
				(width 0.1524)
				(type default)
			)
			(layer "B.SilkS")
		)
		(fp_line
			(start 0.7874 0.4064)
			(end 0.7874 -0.4064)
			(stroke
				(width 0.1524)
				(type default)
			)
			(layer "B.SilkS")
		)
		(fp_line
			(start -0.7874 0.4064)
			(end 0.7874 0.4064)
			(stroke
				(width 0.1524)
				(type default)
			)
			(layer "B.SilkS")
		)
		(fp_line
			(start 0.67945 -0.305054)
			(end 0.12065 -0.305054)
			(stroke
				(width 0.1)
				(type default)
			)
			(layer "B.Fab")
		)
		(fp_line
			(start 0.12065 -0.305054)
			(end 0.12065 -0.2794)
			(stroke
				(width 0.1)
				(type default)
			)
			(layer "B.Fab")
		)
		(fp_line
			(start -0.12065 -0.3048)
			(end -0.67945 -0.3048)
			(stroke
				(width 0.1)
				(type default)
			)
			(layer "B.Fab")
		)
		(fp_line
			(start -0.67945 -0.3048)
			(end -0.67945 0.3048)
			(stroke
				(width 0.1)
				(type default)
			)
			(layer "B.Fab")
		)
		(fp_line
			(start 0.12065 -0.2794)
			(end -0.12065 -0.2794)
			(stroke
				(width 0.1)
				(type default)
			)
			(layer "B.Fab")
		)
		(fp_line
			(start -0.12065 -0.2794)
			(end -0.12065 -0.3048)
			(stroke
				(width 0.1)
				(type default)
			)
			(layer "B.Fab")
		)
		(fp_line
			(start 0.12065 0.2794)
			(end 0.12065 0.3048)
			(stroke
				(width 0.1)
				(type default)
			)
			(layer "B.Fab")
		)
		(fp_line
			(start -0.120396 0.2794)
			(end 0.12065 0.2794)
			(stroke
				(width 0.1)
				(type default)
			)
			(layer "B.Fab")
		)
		(fp_line
			(start 0.67945 0.3048)
			(end 0.67945 -0.305054)
			(stroke
				(width 0.1)
				(type default)
			)
			(layer "B.Fab")
		)
		(fp_line
			(start 0.12065 0.3048)
			(end 0.67945 0.3048)
			(stroke
				(width 0.1)
				(type default)
			)
			(layer "B.Fab")
		)
		(fp_line
			(start -0.120396 0.3048)
			(end -0.120396 0.2794)
			(stroke
				(width 0.1)
				(type default)
			)
			(layer "B.Fab")
		)
		(fp_line
			(start -0.67945 0.3048)
			(end -0.120396 0.3048)
			(stroke
				(width 0.1)
				(type default)
			)
			(layer "B.Fab")
		)
		(pad "1" smd circle
			(at 0.40005 0 270)
			(size 0 0)
			(layers "B.Cu" "B.Mask" "B.Paste")
			(net "P1V2_CPU0_USB2_DVDD12")
		)
		(pad "2" smd circle
			(at -0.40005 0 270)
			(size 0 0)
			(layers "B.Cu" "B.Mask" "B.Paste")
			(net "GND")
		)
	)
)
